# S9S_MB_2U (Grand Teton) — schematic netlist excerpt (pin names and nets, part order shuffled) for the footprints in the layout excerpt that follows; sources: Cadence DE-HDL packaged netlist, KiCad conversion of 03242023_DA0F0TMBIJ0_F0T_Motherboard_J_brd_V01_OCP.brd

R3729  Q_RES  2.2K 5% CHIP  pkg 0402LF  page 233 : A = P3V3_AUX ; B = SMB_LM75_2_3V3AUX_SCL
R3689  Q_RES  4.7K 1% EMPTY  pkg 0402LF  page 250 : A = P3V3_ADC128_VCC ; B = ADC128_VREF

(kicad_pcb
	(version 20260206)
	(generator "pcbnew")
	(generator_version "10.0")
	(general
		(thickness 1.6)
		(legacy_teardrops no)
	)
	(paper "A4")
	(title_block
		(title "03242023_DA0F0TMBIJ0_F0T_Motherboard_J_brd_V01_OCP.brd")
		(comment 1 "Grand Teton / footprints 381-382 of 6105")
	)
	(layers
		(0 "F.Cu" signal "TOP")
		(4 "In1.Cu" signal "GND")
		(6 "In2.Cu" signal "IN1")
		(8 "In3.Cu" signal "GND1")
		(10 "In4.Cu" signal "IN2")
		(12 "In5.Cu" signal "GND2")
		(14 "In6.Cu" signal "IN3")
		(16 "In7.Cu" signal "GND3")
		(18 "In8.Cu" signal "VCC")
		(20 "In9.Cu" signal "VCC1")
		(22 "In10.Cu" signal "GND4")
		(24 "In11.Cu" signal "IN4")
		(26 "In12.Cu" signal "GND5")
		(28 "In13.Cu" signal "IN5")
		(30 "In14.Cu" signal "GND6")
		(32 "In15.Cu" signal "IN6")
		(34 "In16.Cu" signal "GND7")
		(2 "B.Cu" signal "BOTTOM")
		(9 "F.Adhes" user "F.Adhesive")
		(11 "B.Adhes" user "B.Adhesive")
		(13 "F.Paste" user "Package Geometry/Pastemask Top")
		(15 "B.Paste" user "Package Geometry/Pastemask Bottom")
		(5 "F.SilkS" user "Ref Des/Silkscreen Top")
		(7 "B.SilkS" user "Ref Des/Silkscreen Bottom")
		(1 "F.Mask" user "Board Geometry/Soldermask Top")
		(3 "B.Mask" user "Board Geometry/Soldermask Bottom")
		(17 "Dwgs.User" user "User.Drawings")
		(19 "Cmts.User" user "User.Comments")
		(21 "Eco1.User" user "User.Eco1")
		(23 "Eco2.User" user "User.Eco2")
		(25 "Edge.Cuts" user "Board Geometry/Outline")
		(27 "Margin" user)
		(31 "F.CrtYd" user "Package Geometry/Place Bound Top")
		(29 "B.CrtYd" user "Package Geometry/Place Bound Bottom")
		(35 "F.Fab" user "Ref Des/Assembly Top")
		(33 "B.Fab" user "Ref Des/Assembly Bottom")
	)
	(footprint ""
		(layer "F.Cu")
		(at 22.809454 -108.793026 180)
		(property "Reference" "R3689"
			(at 0 0 180)
			(layer "F.SilkS")
			(hide yes)
			(effects
				(font
					(size 1.27 1.27)
				)
			)
		)
		(property "Value" ""
			(at 0 0 180)
			(layer "F.Fab")
			(effects
				(font
					(size 1.27 1.27)
				)
			)
		)
		(duplicate_pad_numbers_are_jumpers no)
		(fp_line
			(start 0.7874 0.4064)
			(end -0.7874 0.4064)
			(stroke
				(width 0.1524)
				(type default)
			)
			(layer "F.SilkS")
		)
		(fp_line
			(start 0.7874 -0.4064)
			(end 0.7874 0.4064)
			(stroke
				(width 0.1524)
				(type default)
			)
			(layer "F.SilkS")
		)
		(fp_line
			(start -0.7874 0.4064)
			(end -0.7874 -0.4064)
			(stroke
				(width 0.1524)
				(type default)
			)
			(layer "F.SilkS")
		)
		(fp_line
			(start -0.7874 -0.4064)
			(end 0.7874 -0.4064)
			(stroke
				(width 0.1524)
				(type default)
			)
			(layer "F.SilkS")
		)
		(fp_line
			(start 0.67945 0.3048)
			(end 0.120396 0.3048)
			(stroke
				(width 0.1)
				(type default)
			)
			(layer "F.Fab")
		)
		(fp_line
			(start 0.67945 -0.3048)
			(end 0.67945 0.3048)
			(stroke
				(width 0.1)
				(type default)
			)
			(layer "F.Fab")
		)
		(fp_line
			(start 0.12065 -0.2794)
			(end 0.12065 -0.3048)
			(stroke
				(width 0.1)
				(type default)
			)
			(layer "F.Fab")
		)
		(fp_line
			(start 0.12065 -0.3048)
			(end 0.67945 -0.3048)
			(stroke
				(width 0.1)
				(type default)
			)
			(layer "F.Fab")
		)
		(fp_line
			(start 0.120396 0.3048)
			(end 0.120396 0.2794)
			(stroke
				(width 0.1)
				(type default)
			)
			(layer "F.Fab")
		)
		(fp_line
			(start 0.120396 0.2794)
			(end -0.12065 0.2794)
			(stroke
				(width 0.1)
				(type default)
			)
			(layer "F.Fab")
		)
		(fp_line
			(start -0.12065 0.3048)
			(end -0.67945 0.3048)
			(stroke
				(width 0.1)
				(type default)
			)
			(layer "F.Fab")
		)
		(fp_line
			(start -0.12065 0.2794)
			(end -0.12065 0.3048)
			(stroke
				(width 0.1)
				(type default)
			)
			(layer "F.Fab")
		)
		(fp_line
			(start -0.12065 -0.2794)
			(end 0.12065 -0.2794)
			(stroke
				(width 0.1)
				(type default)
			)
			(layer "F.Fab")
		)
		(fp_line
			(start -0.12065 -0.305054)
			(end -0.12065 -0.2794)
			(stroke
				(width 0.1)
				(type default)
			)
			(layer "F.Fab")
		)
		(fp_line
			(start -0.67945 0.3048)
			(end -0.67945 -0.305054)
			(stroke
				(width 0.1)
				(type default)
			)
			(layer "F.Fab")
		)
		(fp_line
			(start -0.67945 -0.305054)
			(end -0.12065 -0.305054)
			(stroke
				(width 0.1)
				(type default)
			)
			(layer "F.Fab")
		)
		(pad "1" smd circle
			(at -0.40005 0 180)
			(size 0 0)
			(layers "F.Cu" "F.Mask" "F.Paste")
			(net "P3V3_ADC128_VCC")
		)
		(pad "2" smd circle
			(at 0.40005 0 180)
			(size 0 0)
			(layers "F.Cu" "F.Mask" "F.Paste")
			(net "ADC128_VREF")
		)
	)
	(footprint ""
		(layer "F.Cu")
		(at 51.593496 -105.34777)
		(property "Reference" "R3729"
			(at 0 0 0)
			(layer "F.SilkS")
			(hide yes)
			(effects
				(font
					(size 1.27 1.27)
				)
			)
		)
		(property "Value" ""
			(at 0 0 0)
			(layer "F.Fab")
			(effects
				(font
					(size 1.27 1.27)
				)
			)
		)
		(duplicate_pad_numbers_are_jumpers no)
		(fp_line
			(start -0.7874 -0.4064)
			(end 0.7874 -0.4064)
			(stroke
				(width 0.1524)
				(type default)
			)
			(layer "F.SilkS")
		)
		(fp_line
			(start -0.7874 0.4064)
			(end -0.7874 -0.4064)
			(stroke
				(width 0.1524)
				(type default)
			)
			(layer "F.SilkS")
		)
		(fp_line
			(start 0.7874 -0.4064)
			(end 0.7874 0.4064)
			(stroke
				(width 0.1524)
				(type default)
			)
			(layer "F.SilkS")
		)
		(fp_line
			(start 0.7874 0.4064)
			(end -0.7874 0.4064)
			(stroke
				(width 0.1524)
				(type default)
			)
			(layer "F.SilkS")
		)
		(fp_line
			(start -0.67945 -0.305054)
			(end -0.12065 -0.305054)
			(stroke
				(width 0.1)
				(type default)
			)
			(layer "F.Fab")
		)
		(fp_line
			(start -0.67945 0.3048)
			(end -0.67945 -0.305054)
			(stroke
				(width 0.1)
				(type default)
			)
			(layer "F.Fab")
		)
		(fp_line
			(start -0.12065 -0.305054)
			(end -0.12065 -0.2794)
			(stroke
				(width 0.1)
				(type default)
			)
			(layer "F.Fab")
		)
		(fp_line
			(start -0.12065 -0.2794)
			(end 0.12065 -0.2794)
			(stroke
				(width 0.1)
				(type default)
			)
			(layer "F.Fab")
		)
		(fp_line
			(start -0.12065 0.2794)
			(end -0.12065 0.3048)
			(stroke
				(width 0.1)
				(type default)
			)
			(layer "F.Fab")
		)
		(fp_line
			(start -0.12065 0.3048)
			(end -0.67945 0.3048)
			(stroke
				(width 0.1)
				(type default)
			)
			(layer "F.Fab")
		)
		(fp_line
			(start 0.120396 0.2794)
			(end -0.12065 0.2794)
			(stroke
				(width 0.1)
				(type default)
			)
			(layer "F.Fab")
		)
		(fp_line
			(start 0.120396 0.3048)
			(end 0.120396 0.2794)
			(stroke
				(width 0.1)
				(type default)
			)
			(layer "F.Fab")
		)
		(fp_line
			(start 0.12065 -0.3048)
			(end 0.67945 -0.3048)
			(stroke
				(width 0.1)
				(type default)
			)
			(layer "F.Fab")
		)
		(fp_line
			(start 0.12065 -0.2794)
			(end 0.12065 -0.3048)
			(stroke
				(width 0.1)
				(type default)
			)
			(layer "F.Fab")
		)
		(fp_line
			(start 0.67945 -0.3048)
			(end 0.67945 0.3048)
			(stroke
				(width 0.1)
				(type default)
			)
			(layer "F.Fab")
		)
		(fp_line
			(start 0.67945 0.3048)
			(end 0.120396 0.3048)
			(stroke
				(width 0.1)
				(type default)
			)
			(layer "F.Fab")
		)
		(pad "1" smd circle
			(at -0.40005 0)
			(size 0 0)
			(layers "F.Cu" "F.Mask" "F.Paste")
			(net "P3V3_AUX")
		)
		(pad "2" smd circle
			(at 0.40005 0)
			(size 0 0)
			(layers "F.Cu" "F.Mask" "F.Paste")
			(net "SMB_LM75_2_3V3AUX_SCL")
		)
	)
)
